# S9S_MB_2U (Grand Teton) — schematic netlist excerpt (pin names and nets, part order shuffled) for the footprints in the layout excerpt that follows; sources: Cadence DE-HDL packaged netlist, KiCad conversion of 03242023_DA0F0TMBIJ0_F0T_Motherboard_J_brd_V01_OCP.brd

C1363  Q_CAP  22UF 4V 20% X6S  pkg C0402  page 80 : A = PVNN_MAIN_CPU0 ; B = GND
R3883  Q_RES  49.9 1% CHIP  pkg 0402LF  page 90 : A = I3C_SPD_DDREFGH_CPU0_LVC1_SCL_R ; B = I3C_SPD_DDREFGH_CPU0_LVC1_SCL

(kicad_pcb
	(version 20260206)
	(generator "pcbnew")
	(generator_version "10.0")
	(general
		(thickness 1.6)
		(legacy_teardrops no)
	)
	(paper "A4")
	(title_block
		(title "03242023_DA0F0TMBIJ0_F0T_Motherboard_J_brd_V01_OCP.brd")
		(comment 1 "Grand Teton / footprints 4547-4548 of 6105")
	)
	(layers
		(0 "F.Cu" signal "TOP")
		(4 "In1.Cu" signal "GND")
		(6 "In2.Cu" signal "IN1")
		(8 "In3.Cu" signal "GND1")
		(10 "In4.Cu" signal "IN2")
		(12 "In5.Cu" signal "GND2")
		(14 "In6.Cu" signal "IN3")
		(16 "In7.Cu" signal "GND3")
		(18 "In8.Cu" signal "VCC")
		(20 "In9.Cu" signal "VCC1")
		(22 "In10.Cu" signal "GND4")
		(24 "In11.Cu" signal "IN4")
		(26 "In12.Cu" signal "GND5")
		(28 "In13.Cu" signal "IN5")
		(30 "In14.Cu" signal "GND6")
		(32 "In15.Cu" signal "IN6")
		(34 "In16.Cu" signal "GND7")
		(2 "B.Cu" signal "BOTTOM")
		(9 "F.Adhes" user "F.Adhesive")
		(11 "B.Adhes" user "B.Adhesive")
		(13 "F.Paste" user "Package Geometry/Pastemask Top")
		(15 "B.Paste" user "Package Geometry/Pastemask Bottom")
		(5 "F.SilkS" user "Ref Des/Silkscreen Top")
		(7 "B.SilkS" user "Ref Des/Silkscreen Bottom")
		(1 "F.Mask" user "Board Geometry/Soldermask Top")
		(3 "B.Mask" user "Board Geometry/Soldermask Bottom")
		(17 "Dwgs.User" user "User.Drawings")
		(19 "Cmts.User" user "User.Comments")
		(21 "Eco1.User" user "User.Eco1")
		(23 "Eco2.User" user "User.Eco2")
		(25 "Edge.Cuts" user "Board Geometry/Outline")
		(27 "Margin" user)
		(31 "F.CrtYd" user "Package Geometry/Place Bound Top")
		(29 "B.CrtYd" user "Package Geometry/Place Bound Bottom")
		(35 "F.Fab" user "Ref Des/Assembly Top")
		(33 "B.Fab" user "Ref Des/Assembly Bottom")
	)
	(footprint ""
		(layer "B.Cu")
		(at 446.966848 -184.060592 180)
		(property "Reference" "C1363"
			(at 0 0 0)
			(layer "B.SilkS")
			(hide yes)
			(effects
				(font
					(size 1.27 1.27)
				)
				(justify mirror)
			)
		)
		(property "Value" ""
			(at 0 0 0)
			(layer "B.Fab")
			(effects
				(font
					(size 1.27 1.27)
				)
				(justify mirror)
			)
		)
		(duplicate_pad_numbers_are_jumpers no)
		(fp_line
			(start 0.7874 0.4064)
			(end 0.7874 -0.4064)
			(stroke
				(width 0.1524)
				(type default)
			)
			(layer "B.SilkS")
		)
		(fp_line
			(start 0.7874 -0.4064)
			(end -0.7874 -0.4064)
			(stroke
				(width 0.1524)
				(type default)
			)
			(layer "B.SilkS")
		)
		(fp_line
			(start -0.7874 0.4064)
			(end 0.7874 0.4064)
			(stroke
				(width 0.1524)
				(type default)
			)
			(layer "B.SilkS")
		)
		(fp_line
			(start -0.7874 -0.4064)
			(end -0.7874 0.4064)
			(stroke
				(width 0.1524)
				(type default)
			)
			(layer "B.SilkS")
		)
		(fp_line
			(start 0.67945 0.3048)
			(end 0.67945 -0.305054)
			(stroke
				(width 0.1)
				(type default)
			)
			(layer "B.Fab")
		)
		(fp_line
			(start 0.67945 -0.305054)
			(end 0.12065 -0.305054)
			(stroke
				(width 0.1)
				(type default)
			)
			(layer "B.Fab")
		)
		(fp_line
			(start 0.12065 0.3048)
			(end 0.67945 0.3048)
			(stroke
				(width 0.1)
				(type default)
			)
			(layer "B.Fab")
		)
		(fp_line
			(start 0.12065 0.2794)
			(end 0.12065 0.3048)
			(stroke
				(width 0.1)
				(type default)
			)
			(layer "B.Fab")
		)
		(fp_line
			(start 0.12065 -0.2794)
			(end -0.12065 -0.2794)
			(stroke
				(width 0.1)
				(type default)
			)
			(layer "B.Fab")
		)
		(fp_line
			(start 0.12065 -0.305054)
			(end 0.12065 -0.2794)
			(stroke
				(width 0.1)
				(type default)
			)
			(layer "B.Fab")
		)
		(fp_line
			(start -0.120396 0.3048)
			(end -0.120396 0.2794)
			(stroke
				(width 0.1)
				(type default)
			)
			(layer "B.Fab")
		)
		(fp_line
			(start -0.120396 0.2794)
			(end 0.12065 0.2794)
			(stroke
				(width 0.1)
				(type default)
			)
			(layer "B.Fab")
		)
		(fp_line
			(start -0.12065 -0.2794)
			(end -0.12065 -0.3048)
			(stroke
				(width 0.1)
				(type default)
			)
			(layer "B.Fab")
		)
		(fp_line
			(start -0.12065 -0.3048)
			(end -0.67945 -0.3048)
			(stroke
				(width 0.1)
				(type default)
			)
			(layer "B.Fab")
		)
		(fp_line
			(start -0.67945 0.3048)
			(end -0.120396 0.3048)
			(stroke
				(width 0.1)
				(type default)
			)
			(layer "B.Fab")
		)
		(fp_line
			(start -0.67945 -0.3048)
			(end -0.67945 0.3048)
			(stroke
				(width 0.1)
				(type default)
			)
			(layer "B.Fab")
		)
		(pad "1" smd circle
			(at 0.40005 0)
			(size 0 0)
			(layers "B.Cu" "B.Mask" "B.Paste")
			(net "PVNN_MAIN_CPU0")
		)
		(pad "2" smd circle
			(at -0.40005 0)
			(size 0 0)
			(layers "B.Cu" "B.Mask" "B.Paste")
			(net "GND")
		)
	)
	(footprint ""
		(layer "B.Cu")
		(at 414.41243 -316.621922 90)
		(property "Reference" "R3883"
			(at 0 0 90)
			(layer "B.SilkS")
			(hide yes)
			(effects
				(font
					(size 1.27 1.27)
				)
				(justify mirror)
			)
		)
		(property "Value" ""
			(at 0 0 90)
			(layer "B.Fab")
			(effects
				(font
					(size 1.27 1.27)
				)
				(justify mirror)
			)
		)
		(duplicate_pad_numbers_are_jumpers no)
		(fp_line
			(start 0.7874 -0.4064)
			(end -0.7874 -0.4064)
			(stroke
				(width 0.1524)
				(type default)
			)
			(layer "B.SilkS")
		)
		(fp_line
			(start -0.7874 -0.4064)
			(end -0.7874 0.4064)
			(stroke
				(width 0.1524)
				(type default)
			)
			(layer "B.SilkS")
		)
		(fp_line
			(start 0.7874 0.4064)
			(end 0.7874 -0.4064)
			(stroke
				(width 0.1524)
				(type default)
			)
			(layer "B.SilkS")
		)
		(fp_line
			(start -0.7874 0.4064)
			(end 0.7874 0.4064)
			(stroke
				(width 0.1524)
				(type default)
			)
			(layer "B.SilkS")
		)
		(fp_line
			(start 0.67945 -0.305054)
			(end 0.12065 -0.305054)
			(stroke
				(width 0.1)
				(type default)
			)
			(layer "B.Fab")
		)
		(fp_line
			(start 0.12065 -0.305054)
			(end 0.12065 -0.2794)
			(stroke
				(width 0.1)
				(type default)
			)
			(layer "B.Fab")
		)
		(fp_line
			(start -0.12065 -0.3048)
			(end -0.67945 -0.3048)
			(stroke
				(width 0.1)
				(type default)
			)
			(layer "B.Fab")
		)
		(fp_line
			(start -0.67945 -0.3048)
			(end -0.67945 0.3048)
			(stroke
				(width 0.1)
				(type default)
			)
			(layer "B.Fab")
		)
		(fp_line
			(start 0.12065 -0.2794)
			(end -0.12065 -0.2794)
			(stroke
				(width 0.1)
				(type default)
			)
			(layer "B.Fab")
		)
		(fp_line
			(start -0.12065 -0.2794)
			(end -0.12065 -0.3048)
			(stroke
				(width 0.1)
				(type default)
			)
			(layer "B.Fab")
		)
		(fp_line
			(start 0.12065 0.2794)
			(end 0.12065 0.3048)
			(stroke
				(width 0.1)
				(type default)
			)
			(layer "B.Fab")
		)
		(fp_line
			(start -0.120396 0.2794)
			(end 0.12065 0.2794)
			(stroke
				(width 0.1)
				(type default)
			)
			(layer "B.Fab")
		)
		(fp_line
			(start 0.67945 0.3048)
			(end 0.67945 -0.305054)
			(stroke
				(width 0.1)
				(type default)
			)
			(layer "B.Fab")
		)
		(fp_line
			(start 0.12065 0.3048)
			(end 0.67945 0.3048)
			(stroke
				(width 0.1)
				(type default)
			)
			(layer "B.Fab")
		)
		(fp_line
			(start -0.120396 0.3048)
			(end -0.120396 0.2794)
			(stroke
				(width 0.1)
				(type default)
			)
			(layer "B.Fab")
		)
		(fp_line
			(start -0.67945 0.3048)
			(end -0.120396 0.3048)
			(stroke
				(width 0.1)
				(type default)
			)
			(layer "B.Fab")
		)
		(pad "1" smd circle
			(at 0.40005 0 270)
			(size 0 0)
			(layers "B.Cu" "B.Mask" "B.Paste")
			(net "I3C_SPD_DDREFGH_CPU0_LVC1_SCL_R")
		)
		(pad "2" smd circle
			(at -0.40005 0 270)
			(size 0 0)
			(layers "B.Cu" "B.Mask" "B.Paste")
			(net "I3C_SPD_DDREFGH_CPU0_LVC1_SCL")
		)
	)
)
